# pxlba generated file

# pxlBA.txt : Extract file used to extract properties for
#             back annotation using packagerxl. Refer to Allegro extract
#             documentation for more details on the syntax of this file
#             and the Extract program.

#             The lines starting with # are comments.
#             The default version of this file extracts the minimum number
#             of properties necessary to ba changes to packaging.
#             To extract additional properties the user must remove the
#             comment character '#' from the appropriate lines. Or
#             add a line with the property name to the appropriate section.

#             a2pxl looks for this file in the current working directory.
#             If it is not found there, it looks for it
#             in the hierarchy in the following location:
#                 <installation dir>/tools/pcb/text/views


# Connection view. File: pinView.dat
#
LOGICAL_PIN
# These properties must not be removed, moved or modified.
#  vvvvvvvvvvvvvvvvvvv
   NET_NAME
   REFDES
   PIN_NUMBER
   FUNC_LOGICAL_PATH
   COMP_DEVICE_TYPE
   FUNC_SCH_SIZE
   FUNC_HAS_FIXED_SIZE
   FUNC_DES
#  ^^^^^^^^^^^^^^^^^^^
# Any other PIN properties to be back annotated show up here.
   PIN_PIN_SIGNAL_MODEL
END

# Function properties view. File: funcView.dat
# In order to backannotate function properties you must
# include FUNC_LOGICAL_PATH.
#
FUNCTION
   FUNC_LOGICAL_PATH
   COMP_DEVICE_TYPE
   REFDES
   FUNC_PRIM_FILE
   COMP_PARENT_PPT
   COMP_PARENT_PPT_PART
   COMP_PARENT_PART_TYPE
   FUNC_SCH_SIZE
   FUNC_HAS_FIXED_SIZE
   FUNC_DES
   FUNC_GROUP
   FUNC_ROOM
END

# Component properties view. File: compView.dat
# In order to backannotate component properties you must
# include REFDES
#
COMPONENT
   REFDES
   COMP_PARENT_PPT
   COMP_PARENT_PPT_PART
   COMP_REUSE_ID
   COMP_NO_XNET_CONNECTION
   COMP_MWO_NAME
   COMP_RFGROUP
   COMP_RFDCNET
   COMP_RFBLOCK
   COMP_RFPADTYPE
   COMP_RFDRANAME
   COMP_RFPADANGLE
   COMP_RFHOLEDIAMETER
   COMP_RFPADLENGTH2
   COMP_RFPADLENGTH1
   COMP_RFPADDIAMETER2
   COMP_RFPADDIAMETER1
   COMP_RFPADDIAMETER
   COMP_RFPADLINEWIDTH2
   COMP_RFPADLINEWIDTH1
   COMP_RFPADENDLAYER
   COMP_RFPADBEGINLAYER
   COMP_RFPADSSMNAME2
   COMP_RFPADSSMNAME1
   COMP_RFPADSTACKNAME
   COMP_RFINDUCTANCE
   COMP_RFRESISTANCE
   COMP_RFCAPACITANCE
   COMP_RFNUMBERTURNS
   COMP_RFNUMBERPAIRS
   COMP_RFNUMBERLEGS
   COMP_RFBENDMODE
   COMP_RFMITERFRACTION
   COMP_RFFREQUENCY
   COMP_RFDEPTH
   COMP_RFRADIUS
   COMP_RFOFFSETY
   COMP_RFOFFSETX
   COMP_RFSPACING15
   COMP_RFSPACING14
   COMP_RFSPACING13
   COMP_RFSPACING12
   COMP_RFSPACING11
   COMP_RFSPACING10
   COMP_RFSPACING9
   COMP_RFSPACING8
   COMP_RFSPACING7
   COMP_RFSPACING6
   COMP_RFSPACING5
   COMP_RFSPACING4
   COMP_RFSPACING3
   COMP_RFSPACING2
   COMP_RFSPACING1
   COMP_RFSPACING
   COMP_RFLENGTH8
   COMP_RFLENGTH7
   COMP_RFLENGTH6
   COMP_RFLENGTH5
   COMP_RFLENGTH4
   COMP_RFLENGTH3
   COMP_RFLENGTH2
   COMP_RFLENGTH1
   COMP_RFLENGTH
   COMP_RFWIDTH16
   COMP_RFWIDTH15
   COMP_RFWIDTH14
   COMP_RFWIDTH13
   COMP_RFWIDTH12
   COMP_RFWIDTH11
   COMP_RFWIDTH10
   COMP_RFWIDTH9
   COMP_RFWIDTH8
   COMP_RFWIDTH7
   COMP_RFWIDTH6
   COMP_RFWIDTH5
   COMP_RFWIDTH4
   COMP_RFWIDTH3
   COMP_RFWIDTH2
   COMP_RFWIDTH1
   COMP_RFWIDTH
   COMP_RFANGLE1
   COMP_RFANGLE
   COMP_RFFLIPMODE
   COMP_RFCOUPLINGMODE
   COMP_RFLAYER16
   COMP_RFLAYER15
   COMP_RFLAYER14
   COMP_RFLAYER13
   COMP_RFLAYER12
   COMP_RFLAYER11
   COMP_RFLAYER10
   COMP_RFLAYER9
   COMP_RFLAYER8
   COMP_RFLAYER7
   COMP_RFLAYER6
   COMP_RFLAYER5
   COMP_RFLAYER4
   COMP_RFLAYER3
   COMP_RFLAYER2
   COMP_RFLAYER1
   COMP_RFLAYER
   COMP_RFELEMENTTYPE
   COMP_ISRFELEMENT
   COMP_ASI_MODEL
   COMP_SIGNAL_MODEL
#   The following two properties are needed to feedback ppt
#   part selections done in Allegro.
#   You may comment them out if you do not use this functionality.
COMP_PARENT_PPT
COMP_PARENT_PPT_PART
COMP_REUSE_ID
END

#
# Signal properties view. File: netView.dat
# In order to backannotate signal properties you must
# include NET_NAME
#
NET
   NET_NAME
   NET_LOGICAL_PATH
   NET_RFSPLIT
END
